(kicad_pcb
	(version 20260206)
	(generator "pcbnew")
	(generator_version "10.0")
	(general
		(thickness 1.6)
		(legacy_teardrops no)
	)
	(paper "A4")
	(title_block
		(title "01162023_DA0F0TEBIF0_F0T_Expander_BD_F_brd_V02_OCP.brd")
		(comment 1 "Grand Teton / footprint 4451 of 9728 (PEX3), pads 836-956 of 2397")
	)
	(layers
		(0 "F.Cu" signal "TOP")
		(4 "In1.Cu" signal "GND")
		(6 "In2.Cu" signal "VCC")
		(8 "In3.Cu" signal "VCC1")
		(10 "In4.Cu" signal "GND1")
		(12 "In5.Cu" signal "IN1")
		(14 "In6.Cu" signal "GND2")
		(16 "In7.Cu" signal "IN2")
		(18 "In8.Cu" signal "GND3")
		(20 "In9.Cu" signal "IN3")
		(22 "In10.Cu" signal "GND4")
		(24 "In11.Cu" signal "IN4")
		(26 "In12.Cu" signal "GND5")
		(28 "In13.Cu" signal "IN5")
		(30 "In14.Cu" signal "GND6")
		(32 "In15.Cu" signal "IN6")
		(34 "In16.Cu" signal "GND7")
		(2 "B.Cu" signal "BOTTOM")
		(9 "F.Adhes" user "F.Adhesive")
		(11 "B.Adhes" user "B.Adhesive")
		(13 "F.Paste" user "Package Geometry/Pastemask Top")
		(15 "B.Paste" user "Package Geometry/Pastemask Bottom")
		(5 "F.SilkS" user "Ref Des/Silkscreen Top")
		(7 "B.SilkS" user "Ref Des/Silkscreen Bottom")
		(1 "F.Mask" user "Board Geometry/Soldermask Top")
		(3 "B.Mask" user "Board Geometry/Soldermask Bottom")
		(17 "Dwgs.User" user "User.Drawings")
		(19 "Cmts.User" user "User.Comments")
		(21 "Eco1.User" user "User.Eco1")
		(23 "Eco2.User" user "User.Eco2")
		(25 "Edge.Cuts" user "Board Geometry/Outline")
		(27 "Margin" user)
		(31 "F.CrtYd" user "Package Geometry/Place Bound Top")
		(29 "B.CrtYd" user "Package Geometry/Place Bound Bottom")
		(35 "F.Fab" user "Ref Des/Assembly Top")
		(33 "B.Fab" user "Ref Des/Assembly Bottom")
	)
	(footprint ""
		(layer "F.Cu")
		(at 407.949908 -295.89984)
		(property "Reference" "PEX3"
			(at -3.358642 35.5727 0)
			(unlocked yes)
			(layer "F.SilkS")
			(effects
				(font
					(size 2.032 1.524)
					(thickness 0.1524)
				)
				(justify left)
			)
		)
		(property "Value" ""
			(at 0 0 0)
			(layer "F.Fab")
			(effects
				(font
					(size 1.27 1.27)
				)
			)
		)
		(duplicate_pad_numbers_are_jumpers no)
		(pad "AU5" smd circle
			(at -18.999962 11.400028)
			(size 0.4572 0.4572)
			(layers "F.Cu" "F.Mask" "F.Paste")
			(net "GND")
		)
		(pad "AU6" smd circle
			(at -18.050002 11.400028)
			(size 0.4572 0.4572)
			(layers "F.Cu" "F.Mask" "F.Paste")
			(net "Net_1401")
		)
		(pad "AU7" smd circle
			(at -17.100042 11.400028)
			(size 0.4572 0.4572)
			(layers "F.Cu" "F.Mask" "F.Paste")
			(net "Net_1354")
		)
		(pad "AU8" smd circle
			(at -16.150082 11.400028)
			(size 0.4572 0.4572)
			(layers "F.Cu" "F.Mask" "F.Paste")
			(net "GND")
		)
		(pad "AU9" smd circle
			(at -15.200122 11.400028)
			(size 0.4572 0.4572)
			(layers "F.Cu" "F.Mask" "F.Paste")
			(net "GND")
		)
		(pad "AU10" smd circle
			(at -14.249908 11.400028)
			(size 0.4572 0.4572)
			(layers "F.Cu" "F.Mask" "F.Paste")
			(net "GND")
		)
		(pad "AU11" smd circle
			(at -13.299948 11.400028)
			(size 0.4572 0.4572)
			(layers "F.Cu" "F.Mask" "F.Paste")
			(net "GND")
		)
		(pad "AU12" smd circle
			(at -12.349988 11.400028)
			(size 0.4572 0.4572)
			(layers "F.Cu" "F.Mask" "F.Paste")
			(net "GND")
		)
		(pad "AU13" smd circle
			(at -11.400028 11.400028)
			(size 0.4572 0.4572)
			(layers "F.Cu" "F.Mask" "F.Paste")
			(net "GND")
		)
		(pad "AU14" smd circle
			(at -10.450068 11.400028)
			(size 0.4572 0.4572)
			(layers "F.Cu" "F.Mask" "F.Paste")
			(net "GND")
		)
		(pad "AU15" smd circle
			(at -9.500108 11.400028)
			(size 0.4572 0.4572)
			(layers "F.Cu" "F.Mask" "F.Paste")
			(net "GND")
		)
		(pad "AU16" smd circle
			(at -8.549894 11.400028)
			(size 0.4572 0.4572)
			(layers "F.Cu" "F.Mask" "F.Paste")
			(net "GND")
		)
		(pad "AU17" smd circle
			(at -7.599934 11.400028)
			(size 0.4572 0.4572)
			(layers "F.Cu" "F.Mask" "F.Paste")
			(net "GND")
		)
		(pad "AU18" smd circle
			(at -6.649974 11.400028)
			(size 0.4572 0.4572)
			(layers "F.Cu" "F.Mask" "F.Paste")
			(net "GND")
		)
		(pad "AU19" smd circle
			(at -5.700014 11.400028)
			(size 0.4572 0.4572)
			(layers "F.Cu" "F.Mask" "F.Paste")
			(net "GND")
		)
		(pad "AU20" smd circle
			(at -4.750054 11.400028)
			(size 0.4572 0.4572)
			(layers "F.Cu" "F.Mask" "F.Paste")
			(net "GND")
		)
		(pad "AU21" smd circle
			(at -3.800094 11.400028)
			(size 0.4572 0.4572)
			(layers "F.Cu" "F.Mask" "F.Paste")
			(net "GND")
		)
		(pad "AU22" smd circle
			(at -2.84988 11.400028)
			(size 0.4572 0.4572)
			(layers "F.Cu" "F.Mask" "F.Paste")
			(net "GND")
		)
		(pad "AU23" smd circle
			(at -1.89992 11.400028)
			(size 0.4572 0.4572)
			(layers "F.Cu" "F.Mask" "F.Paste")
			(net "GND")
		)
		(pad "AU24" smd circle
			(at -0.94996 11.400028)
			(size 0.4572 0.4572)
			(layers "F.Cu" "F.Mask" "F.Paste")
			(net "GND")
		)
		(pad "AU25" smd circle
			(at 0 11.400028)
			(size 0.4572 0.4572)
			(layers "F.Cu" "F.Mask" "F.Paste")
			(net "GND")
		)
		(pad "AU26" smd circle
			(at 0.94996 11.400028)
			(size 0.4572 0.4572)
			(layers "F.Cu" "F.Mask" "F.Paste")
			(net "GND")
		)
		(pad "AU27" smd circle
			(at 1.89992 11.400028)
			(size 0.4572 0.4572)
			(layers "F.Cu" "F.Mask" "F.Paste")
			(net "GND")
		)
		(pad "AU28" smd circle
			(at 2.84988 11.400028)
			(size 0.4572 0.4572)
			(layers "F.Cu" "F.Mask" "F.Paste")
			(net "GND")
		)
		(pad "AU29" smd circle
			(at 3.800094 11.400028)
			(size 0.4572 0.4572)
			(layers "F.Cu" "F.Mask" "F.Paste")
			(net "GND")
		)
		(pad "AU30" smd circle
			(at 4.750054 11.400028)
			(size 0.4572 0.4572)
			(layers "F.Cu" "F.Mask" "F.Paste")
			(net "GND")
		)
		(pad "AU31" smd circle
			(at 5.700014 11.400028)
			(size 0.4572 0.4572)
			(layers "F.Cu" "F.Mask" "F.Paste")
			(net "GND")
		)
		(pad "AU32" smd circle
			(at 6.649974 11.400028)
			(size 0.4572 0.4572)
			(layers "F.Cu" "F.Mask" "F.Paste")
			(net "GND")
		)
		(pad "AU33" smd circle
			(at 7.599934 11.400028)
			(size 0.4572 0.4572)
			(layers "F.Cu" "F.Mask" "F.Paste")
			(net "GND")
		)
		(pad "AU34" smd circle
			(at 8.549894 11.400028)
			(size 0.4572 0.4572)
			(layers "F.Cu" "F.Mask" "F.Paste")
			(net "GND")
		)
		(pad "AU35" smd circle
			(at 9.500108 11.400028)
			(size 0.4572 0.4572)
			(layers "F.Cu" "F.Mask" "F.Paste")
			(net "GND")
		)
		(pad "AU36" smd circle
			(at 10.450068 11.400028)
			(size 0.4572 0.4572)
			(layers "F.Cu" "F.Mask" "F.Paste")
			(net "GND")
		)
		(pad "AU37" smd circle
			(at 11.400028 11.400028)
			(size 0.4572 0.4572)
			(layers "F.Cu" "F.Mask" "F.Paste")
			(net "GND")
		)
		(pad "AU38" smd circle
			(at 12.349988 11.400028)
			(size 0.4572 0.4572)
			(layers "F.Cu" "F.Mask" "F.Paste")
			(net "Net_5448")
		)
		(pad "AU39" smd circle
			(at 13.299948 11.400028)
			(size 0.4572 0.4572)
			(layers "F.Cu" "F.Mask" "F.Paste")
			(net "Net_5420")
		)
		(pad "AU40" smd circle
			(at 14.249908 11.400028)
			(size 0.4572 0.4572)
			(layers "F.Cu" "F.Mask" "F.Paste")
			(net "GND")
		)
		(pad "AU41" smd circle
			(at 15.200122 11.400028)
			(size 0.4572 0.4572)
			(layers "F.Cu" "F.Mask" "F.Paste")
			(net "GND")
		)
		(pad "AU42" smd circle
			(at 16.150082 11.400028)
			(size 0.4572 0.4572)
			(layers "F.Cu" "F.Mask" "F.Paste")
			(net "GND")
		)
		(pad "AU43" smd circle
			(at 17.100042 11.400028)
			(size 0.4572 0.4572)
			(layers "F.Cu" "F.Mask" "F.Paste")
			(net "P5E_PEX3_STN0_TX_DP<4>")
		)
		(pad "AU44" smd circle
			(at 18.050002 11.400028)
			(size 0.4572 0.4572)
			(layers "F.Cu" "F.Mask" "F.Paste")
			(net "P5E_PEX3_STN0_TX_DN<4>")
		)
		(pad "AU45" smd circle
			(at 18.999962 11.400028)
			(size 0.4572 0.4572)
			(layers "F.Cu" "F.Mask" "F.Paste")
			(net "GND")
		)
		(pad "AU46" smd circle
			(at 19.949922 11.400028)
			(size 0.4572 0.4572)
			(layers "F.Cu" "F.Mask" "F.Paste")
			(net "P5E_PEX3_STN0_RX_DP<4>")
		)
		(pad "AU47" smd circle
			(at 20.899882 11.400028)
			(size 0.4572 0.4572)
			(layers "F.Cu" "F.Mask" "F.Paste")
			(net "P5E_PEX3_STN0_RX_DN<4>")
		)
		(pad "AU48" smd circle
			(at 21.850096 11.400028)
			(size 0.4572 0.4572)
			(layers "F.Cu" "F.Mask" "F.Paste")
			(net "GND")
		)
		(pad "AU49" smd circle
			(at 22.800056 11.400028)
			(size 0.4572 0.4572)
			(layers "F.Cu" "F.Mask" "F.Paste")
			(net "GND")
		)
		(pad "AV1" smd circle
			(at -22.800056 12.349988)
			(size 0.4572 0.4572)
			(layers "F.Cu" "F.Mask" "F.Paste")
			(net "Net_1485")
		)
		(pad "AV2" smd circle
			(at -21.850096 12.349988)
			(size 0.4572 0.4572)
			(layers "F.Cu" "F.Mask" "F.Paste")
			(net "Net_1507")
		)
		(pad "AV3" smd circle
			(at -20.899882 12.349988)
			(size 0.4572 0.4572)
			(layers "F.Cu" "F.Mask" "F.Paste")
			(net "GND")
		)
		(pad "AV4" smd circle
			(at -19.949922 12.349988)
			(size 0.4572 0.4572)
			(layers "F.Cu" "F.Mask" "F.Paste")
			(net "GND")
		)
		(pad "AV5" smd circle
			(at -18.999962 12.349988)
			(size 0.4572 0.4572)
			(layers "F.Cu" "F.Mask" "F.Paste")
			(net "GND")
		)
		(pad "AV6" smd circle
			(at -18.050002 12.349988)
			(size 0.4572 0.4572)
			(layers "F.Cu" "F.Mask" "F.Paste")
			(net "GND")
		)
		(pad "AV7" smd circle
			(at -17.100042 12.349988)
			(size 0.4572 0.4572)
			(layers "F.Cu" "F.Mask" "F.Paste")
			(net "GND")
		)
		(pad "AV8" smd circle
			(at -16.150082 12.349988)
			(size 0.4572 0.4572)
			(layers "F.Cu" "F.Mask" "F.Paste")
			(net "Net_1365")
		)
		(pad "AV9" smd circle
			(at -15.200122 12.349988)
			(size 0.4572 0.4572)
			(layers "F.Cu" "F.Mask" "F.Paste")
			(net "Net_1481")
		)
		(pad "AV10" smd circle
			(at -14.249908 12.349988)
			(size 0.4572 0.4572)
			(layers "F.Cu" "F.Mask" "F.Paste")
			(net "GND")
		)
		(pad "AV11" smd circle
			(at -13.299948 12.349988)
			(size 0.4572 0.4572)
			(layers "F.Cu" "F.Mask" "F.Paste")
			(net "GND")
		)
		(pad "AV12" smd circle
			(at -12.349988 12.349988)
			(size 0.4572 0.4572)
			(layers "F.Cu" "F.Mask" "F.Paste")
			(net "Net_5438")
		)
		(pad "AV13" smd circle
			(at -11.400028 12.349988)
			(size 0.4572 0.4572)
			(layers "F.Cu" "F.Mask" "F.Paste")
			(net "Net_5439")
		)
		(pad "AV14" smd circle
			(at -10.450068 12.349988)
			(size 0.4572 0.4572)
			(layers "F.Cu" "F.Mask" "F.Paste")
			(net "Net_5430")
		)
		(pad "AV15" smd circle
			(at -9.500108 12.349988)
			(size 0.4572 0.4572)
			(layers "F.Cu" "F.Mask" "F.Paste")
			(net "Net_5424")
		)
		(pad "AV16" smd circle
			(at -8.549894 12.349988)
			(size 0.4572 0.4572)
			(layers "F.Cu" "F.Mask" "F.Paste")
			(net "Net_5433")
		)
		(pad "AV17" smd circle
			(at -7.599934 12.349988)
			(size 0.4572 0.4572)
			(layers "F.Cu" "F.Mask" "F.Paste")
			(net "Net_5434")
		)
		(pad "AV18" smd circle
			(at -6.649974 12.349988)
			(size 0.4572 0.4572)
			(layers "F.Cu" "F.Mask" "F.Paste")
			(net "Net_5429")
		)
		(pad "AV19" smd circle
			(at -5.700014 12.349988)
			(size 0.4572 0.4572)
			(layers "F.Cu" "F.Mask" "F.Paste")
			(net "Net_5425")
		)
		(pad "AV20" smd circle
			(at -4.750054 12.349988)
			(size 0.4572 0.4572)
			(layers "F.Cu" "F.Mask" "F.Paste")
			(net "GND")
		)
		(pad "AV21" smd circle
			(at -3.800094 12.349988)
			(size 0.4572 0.4572)
			(layers "F.Cu" "F.Mask" "F.Paste")
			(net "Net_5464")
		)
		(pad "AV22" smd circle
			(at -2.84988 12.349988)
			(size 0.4572 0.4572)
			(layers "F.Cu" "F.Mask" "F.Paste")
			(net "Net_5465")
		)
		(pad "AV23" smd circle
			(at -1.89992 12.349988)
			(size 0.4572 0.4572)
			(layers "F.Cu" "F.Mask" "F.Paste")
			(net "Net_5467")
		)
		(pad "AV24" smd circle
			(at -0.94996 12.349988)
			(size 0.4572 0.4572)
			(layers "F.Cu" "F.Mask" "F.Paste")
			(net "GND")
		)
		(pad "AV25" smd circle
			(at 0 12.349988)
			(size 0.4572 0.4572)
			(layers "F.Cu" "F.Mask" "F.Paste")
			(net "PEX3_MODE_SEL2")
		)
		(pad "AV26" smd circle
			(at 0.94996 12.349988)
			(size 0.4572 0.4572)
			(layers "F.Cu" "F.Mask" "F.Paste")
			(net "PEX3_MODE_SEL7")
		)
		(pad "AV27" smd circle
			(at 1.89992 12.349988)
			(size 0.4572 0.4572)
			(layers "F.Cu" "F.Mask" "F.Paste")
			(net "PEX3_MODE_SEL3")
		)
		(pad "AV28" smd circle
			(at 2.84988 12.349988)
			(size 0.4572 0.4572)
			(layers "F.Cu" "F.Mask" "F.Paste")
			(net "PEX3_MODE_SEL9")
		)
		(pad "AV29" smd circle
			(at 3.800094 12.349988)
			(size 0.4572 0.4572)
			(layers "F.Cu" "F.Mask" "F.Paste")
			(net "PEX3_PCA9555_INT_R_N")
		)
		(pad "AV30" smd circle
			(at 4.750054 12.349988)
			(size 0.4572 0.4572)
			(layers "F.Cu" "F.Mask" "F.Paste")
			(net "PEX3_SYS_ERR_N")
		)
		(pad "AV31" smd circle
			(at 5.700014 12.349988)
			(size 0.4572 0.4572)
			(layers "F.Cu" "F.Mask" "F.Paste")
			(net "PEX3_MODE_SEL6")
		)
		(pad "AV32" smd circle
			(at 6.649974 12.349988)
			(size 0.4572 0.4572)
			(layers "F.Cu" "F.Mask" "F.Paste")
			(net "PEX3_MODE_SEL10")
		)
		(pad "AV33" smd circle
			(at 7.599934 12.349988)
			(size 0.4572 0.4572)
			(layers "F.Cu" "F.Mask" "F.Paste")
			(net "Net_5442")
		)
		(pad "AV34" smd circle
			(at 8.549894 12.349988)
			(size 0.4572 0.4572)
			(layers "F.Cu" "F.Mask" "F.Paste")
			(net "Net_5415")
		)
		(pad "AV35" smd circle
			(at 9.500108 12.349988)
			(size 0.4572 0.4572)
			(layers "F.Cu" "F.Mask" "F.Paste")
			(net "Net_5444")
		)
		(pad "AV36" smd circle
			(at 10.450068 12.349988)
			(size 0.4572 0.4572)
			(layers "F.Cu" "F.Mask" "F.Paste")
			(net "Net_5421")
		)
		(pad "AV37" smd circle
			(at 11.400028 12.349988)
			(size 0.4572 0.4572)
			(layers "F.Cu" "F.Mask" "F.Paste")
			(net "Net_5446")
		)
		(pad "AV38" smd circle
			(at 12.349988 12.349988)
			(size 0.4572 0.4572)
			(layers "F.Cu" "F.Mask" "F.Paste")
			(net "Net_5445")
		)
		(pad "AV39" smd circle
			(at 13.299948 12.349988)
			(size 0.4572 0.4572)
			(layers "F.Cu" "F.Mask" "F.Paste")
			(net "Net_5437")
		)
		(pad "AV40" smd circle
			(at 14.249908 12.349988)
			(size 0.4572 0.4572)
			(layers "F.Cu" "F.Mask" "F.Paste")
			(net "GND")
		)
		(pad "AV41" smd circle
			(at 15.200122 12.349988)
			(size 0.4572 0.4572)
			(layers "F.Cu" "F.Mask" "F.Paste")
			(net "P5E_PEX3_STN0_TX_DP<5>")
		)
		(pad "AV42" smd circle
			(at 16.150082 12.349988)
			(size 0.4572 0.4572)
			(layers "F.Cu" "F.Mask" "F.Paste")
			(net "P5E_PEX3_STN0_TX_DN<5>")
		)
		(pad "AV43" smd circle
			(at 17.100042 12.349988)
			(size 0.4572 0.4572)
			(layers "F.Cu" "F.Mask" "F.Paste")
			(net "GND")
		)
		(pad "AV44" smd circle
			(at 18.050002 12.349988)
			(size 0.4572 0.4572)
			(layers "F.Cu" "F.Mask" "F.Paste")
			(net "GND")
		)
		(pad "AV45" smd circle
			(at 18.999962 12.349988)
			(size 0.4572 0.4572)
			(layers "F.Cu" "F.Mask" "F.Paste")
			(net "GND")
		)
		(pad "AV46" smd circle
			(at 19.949922 12.349988)
			(size 0.4572 0.4572)
			(layers "F.Cu" "F.Mask" "F.Paste")
			(net "GND")
		)
		(pad "AV47" smd circle
			(at 20.899882 12.349988)
			(size 0.4572 0.4572)
			(layers "F.Cu" "F.Mask" "F.Paste")
			(net "GND")
		)
		(pad "AV48" smd circle
			(at 21.850096 12.349988)
			(size 0.4572 0.4572)
			(layers "F.Cu" "F.Mask" "F.Paste")
			(net "P5E_PEX3_STN0_RX_DP<5>")
		)
		(pad "AV49" smd circle
			(at 22.800056 12.349988)
			(size 0.4572 0.4572)
			(layers "F.Cu" "F.Mask" "F.Paste")
			(net "P5E_PEX3_STN0_RX_DN<5>")
		)
		(pad "AW1" smd circle
			(at -22.800056 13.299948)
			(size 0.4572 0.4572)
			(layers "F.Cu" "F.Mask" "F.Paste")
			(net "GND")
		)
		(pad "AW2" smd circle
			(at -21.850096 13.299948)
			(size 0.4572 0.4572)
			(layers "F.Cu" "F.Mask" "F.Paste")
			(net "GND")
		)
		(pad "AW3" smd circle
			(at -20.899882 13.299948)
			(size 0.4572 0.4572)
			(layers "F.Cu" "F.Mask" "F.Paste")
			(net "Net_1513")
		)
		(pad "AW4" smd circle
			(at -19.949922 13.299948)
			(size 0.4572 0.4572)
			(layers "F.Cu" "F.Mask" "F.Paste")
			(net "Net_1505")
		)
		(pad "AW5" smd circle
			(at -18.999962 13.299948)
			(size 0.4572 0.4572)
			(layers "F.Cu" "F.Mask" "F.Paste")
			(net "GND")
		)
		(pad "AW6" smd circle
			(at -18.050002 13.299948)
			(size 0.4572 0.4572)
			(layers "F.Cu" "F.Mask" "F.Paste")
			(net "Net_1376")
		)
		(pad "AW7" smd circle
			(at -17.100042 13.299948)
			(size 0.4572 0.4572)
			(layers "F.Cu" "F.Mask" "F.Paste")
			(net "Net_1378")
		)
		(pad "AW8" smd circle
			(at -16.150082 13.299948)
			(size 0.4572 0.4572)
			(layers "F.Cu" "F.Mask" "F.Paste")
			(net "GND")
		)
		(pad "AW9" smd circle
			(at -15.200122 13.299948)
			(size 0.4572 0.4572)
			(layers "F.Cu" "F.Mask" "F.Paste")
			(net "GND")
		)
		(pad "AW10" smd circle
			(at -14.249908 13.299948)
			(size 0.4572 0.4572)
			(layers "F.Cu" "F.Mask" "F.Paste")
			(net "GND")
		)
		(pad "AW11" smd circle
			(at -13.299948 13.299948)
			(size 0.4572 0.4572)
			(layers "F.Cu" "F.Mask" "F.Paste")
			(net "GND")
		)
		(pad "AW12" smd circle
			(at -12.349988 13.299948)
			(size 0.4572 0.4572)
			(layers "F.Cu" "F.Mask" "F.Paste")
			(net "Net_5436")
		)
		(pad "AW13" smd circle
			(at -11.400028 13.299948)
			(size 0.4572 0.4572)
			(layers "F.Cu" "F.Mask" "F.Paste")
			(net "Net_5432")
		)
		(pad "AW14" smd circle
			(at -10.450068 13.299948)
			(size 0.4572 0.4572)
			(layers "F.Cu" "F.Mask" "F.Paste")
			(net "Net_5428")
		)
		(pad "AW15" smd circle
			(at -9.500108 13.299948)
			(size 0.4572 0.4572)
			(layers "F.Cu" "F.Mask" "F.Paste")
			(net "Net_5423")
		)
		(pad "AW16" smd circle
			(at -8.549894 13.299948)
			(size 0.4572 0.4572)
			(layers "F.Cu" "F.Mask" "F.Paste")
			(net "Net_5435")
		)
		(pad "AW17" smd circle
			(at -7.599934 13.299948)
			(size 0.4572 0.4572)
			(layers "F.Cu" "F.Mask" "F.Paste")
			(net "Net_5431")
		)
		(pad "AW18" smd circle
			(at -6.649974 13.299948)
			(size 0.4572 0.4572)
			(layers "F.Cu" "F.Mask" "F.Paste")
			(net "Net_5427")
		)
		(pad "AW19" smd circle
			(at -5.700014 13.299948)
			(size 0.4572 0.4572)
			(layers "F.Cu" "F.Mask" "F.Paste")
			(net "Net_5422")
		)
		(pad "AW20" smd circle
			(at -4.750054 13.299948)
			(size 0.4572 0.4572)
			(layers "F.Cu" "F.Mask" "F.Paste")
			(net "GND")
		)
		(pad "AW21" smd circle
			(at -3.800094 13.299948)
			(size 0.4572 0.4572)
			(layers "F.Cu" "F.Mask" "F.Paste")
			(net "Net_5456")
		)
		(pad "AW22" smd circle
			(at -2.84988 13.299948)
			(size 0.4572 0.4572)
			(layers "F.Cu" "F.Mask" "F.Paste")
			(net "Net_5466")
		)
		(pad "AW23" smd circle
			(at -1.89992 13.299948)
			(size 0.4572 0.4572)
			(layers "F.Cu" "F.Mask" "F.Paste")
			(net "Net_5455")
		)
		(pad "AW24" smd circle
			(at -0.94996 13.299948)
			(size 0.4572 0.4572)
			(layers "F.Cu" "F.Mask" "F.Paste")
			(net "GND")
		)
		(pad "AW25" smd circle
			(at 0 13.299948)
			(size 0.4572 0.4572)
			(layers "F.Cu" "F.Mask" "F.Paste")
			(net "PEX3_MODE_SEL5")
		)
		(pad "AW26" smd circle
			(at 0.94996 13.299948)
			(size 0.4572 0.4572)
			(layers "F.Cu" "F.Mask" "F.Paste")
			(net "PEX3_DBG_MODE3")
		)
		(pad "AW27" smd circle
			(at 1.89992 13.299948)
			(size 0.4572 0.4572)
			(layers "F.Cu" "F.Mask" "F.Paste")
			(net "PEX3_MODE_SEL0")
		)
	)
)
